(kicad_pcb
	(version 20260206)
	(generator "pcbnew")
	(generator_version "10.0")
	(general
		(thickness 1.6)
		(legacy_teardrops no)
	)
	(paper "A4")
	(title_block
		(title "Bryce Canyon_SCC_16316-1_OCP.brd")
		(comment 1 "Bryce Canyon / footprints 9-16 of 1561")
	)
	(layers
		(0 "F.Cu" signal "TOP")
		(4 "In1.Cu" signal "L2GND")
		(6 "In2.Cu" signal "L3")
		(8 "In3.Cu" signal "L4VCC")
		(10 "In4.Cu" signal "L5VCC")
		(12 "In5.Cu" signal "L6")
		(14 "In6.Cu" signal "L7GND")
		(2 "B.Cu" signal "BOTTOM")
		(9 "F.Adhes" user "F.Adhesive")
		(11 "B.Adhes" user "B.Adhesive")
		(13 "F.Paste" user "Package Geometry/Pastemask Top")
		(15 "B.Paste" user "Package Geometry/Pastemask Bottom")
		(5 "F.SilkS" user "Ref Des/Silkscreen Top")
		(7 "B.SilkS" user "Ref Des/Silkscreen Bottom")
		(1 "F.Mask" user "Board Geometry/Soldermask Top")
		(3 "B.Mask" user "Board Geometry/Soldermask Bottom")
		(17 "Dwgs.User" user "User.Drawings")
		(19 "Cmts.User" user "User.Comments")
		(21 "Eco1.User" user "User.Eco1")
		(23 "Eco2.User" user "User.Eco2")
		(25 "Edge.Cuts" user "Board Geometry/Outline")
		(27 "Margin" user)
		(31 "F.CrtYd" user "Package Geometry/Place Bound Top")
		(29 "B.CrtYd" user "Package Geometry/Place Bound Bottom")
		(35 "F.Fab" user "Ref Des/Assembly Top")
		(33 "B.Fab" user "Ref Des/Assembly Bottom")
	)
	(footprint ""
		(layer "F.Cu")
		(at 19.2786 -74.0918 90)
		(property "Reference" "C530"
			(at 0 0 90)
			(layer "F.SilkS")
			(hide yes)
			(effects
				(font
					(size 1.27 1.27)
				)
			)
		)
		(property "Value" "SCD1U16V2KX-3GP"
			(at 1.1811 -2.7051 90)
			(unlocked yes)
			(layer "F.Fab")
			(hide yes)
			(effects
				(font
					(size 1.016 1.016)
					(thickness 0.1524)
				)
			)
		)
		(property "Device Type" "C402H22"
			(at 1.1811 -4.2291 90)
			(unlocked yes)
			(layer "F.Fab")
			(hide yes)
			(effects
				(font
					(size 1.016 1.016)
					(thickness 0.1524)
				)
			)
		)
		(duplicate_pad_numbers_are_jumpers no)
		(fp_rect
			(start -0.4318 0.9525)
			(end 0.4318 -0.9525)
			(stroke
				(width 0)
				(type default)
			)
			(fill no)
			(layer "F.CrtYd")
		)
		(fp_rect
			(start -0.4318 0.9525)
			(end 0.4318 -0.9525)
			(stroke
				(width 0)
				(type default)
			)
			(fill no)
			(layer "F.Fab")
		)
		(pad "1" smd custom
			(at 0 -0.4445 90)
			(size 0.1524 0.1524)
			(layers "F.Cu" "F.Mask" "F.Paste")
			(net "P3V3")
			(options
				(clearance outline)
				(anchor circle)
			)
			(primitives
				(gr_poly
					(pts
						(arc
							(start 0.3048 -0.2032)
							(mid 0.275042 -0.275042)
							(end 0.2032 -0.3048)
						)
						(arc
							(start -0.2032 -0.3048)
							(mid -0.275042 -0.275042)
							(end -0.3048 -0.2032)
						)
						(arc
							(start -0.3048 0.2032)
							(mid -0.275042 0.275042)
							(end -0.2032 0.3048)
						)
						(arc
							(start 0.2032 0.3048)
							(mid 0.275042 0.275042)
							(end 0.3048 0.2032)
						)
					)
					(width 0)
					(fill yes)
				)
			)
		)
		(pad "2" smd custom
			(at 0 0.4445 90)
			(size 0.1524 0.1524)
			(layers "F.Cu" "F.Mask" "F.Paste")
			(net "GND")
			(options
				(clearance outline)
				(anchor circle)
			)
			(primitives
				(gr_poly
					(pts
						(arc
							(start 0.3048 -0.2032)
							(mid 0.275042 -0.275042)
							(end 0.2032 -0.3048)
						)
						(arc
							(start -0.2032 -0.3048)
							(mid -0.275042 -0.275042)
							(end -0.3048 -0.2032)
						)
						(arc
							(start -0.3048 0.2032)
							(mid -0.275042 0.275042)
							(end -0.2032 0.3048)
						)
						(arc
							(start 0.2032 0.3048)
							(mid 0.275042 0.275042)
							(end 0.3048 0.2032)
						)
					)
					(width 0)
					(fill yes)
				)
			)
		)
	)
	(footprint ""
		(layer "F.Cu")
		(at 70.440804 -70.696582 -90)
		(property "Reference" "C559"
			(at 0 0 270)
			(layer "F.SilkS")
			(hide yes)
			(effects
				(font
					(size 1.27 1.27)
				)
			)
		)
		(property "Value" "SCD1U16V2KX-3GP"
			(at 1.1811 -2.7051 270)
			(unlocked yes)
			(layer "F.Fab")
			(hide yes)
			(effects
				(font
					(size 1.016 1.016)
					(thickness 0.1524)
				)
			)
		)
		(property "Device Type" "C402H22"
			(at 1.1811 -4.2291 270)
			(unlocked yes)
			(layer "F.Fab")
			(hide yes)
			(effects
				(font
					(size 1.016 1.016)
					(thickness 0.1524)
				)
			)
		)
		(duplicate_pad_numbers_are_jumpers no)
		(fp_rect
			(start -0.4318 0.9525)
			(end 0.4318 -0.9525)
			(stroke
				(width 0)
				(type default)
			)
			(fill no)
			(layer "F.CrtYd")
		)
		(fp_rect
			(start -0.4318 0.9525)
			(end 0.4318 -0.9525)
			(stroke
				(width 0)
				(type default)
			)
			(fill no)
			(layer "F.Fab")
		)
		(pad "1" smd custom
			(at 0 -0.4445 270)
			(size 0.1524 0.1524)
			(layers "F.Cu" "F.Mask" "F.Paste")
			(net "VREF6")
			(options
				(clearance outline)
				(anchor circle)
			)
			(primitives
				(gr_poly
					(pts
						(arc
							(start 0.3048 -0.2032)
							(mid 0.275042 -0.275042)
							(end 0.2032 -0.3048)
						)
						(arc
							(start -0.2032 -0.3048)
							(mid -0.275042 -0.275042)
							(end -0.3048 -0.2032)
						)
						(arc
							(start -0.3048 0.2032)
							(mid -0.275042 0.275042)
							(end -0.2032 0.3048)
						)
						(arc
							(start 0.2032 0.3048)
							(mid 0.275042 0.275042)
							(end 0.3048 0.2032)
						)
					)
					(width 0)
					(fill yes)
				)
			)
		)
		(pad "2" smd custom
			(at 0 0.4445 270)
			(size 0.1524 0.1524)
			(layers "F.Cu" "F.Mask" "F.Paste")
			(net "GND")
			(options
				(clearance outline)
				(anchor circle)
			)
			(primitives
				(gr_poly
					(pts
						(arc
							(start 0.3048 -0.2032)
							(mid 0.275042 -0.275042)
							(end 0.2032 -0.3048)
						)
						(arc
							(start -0.2032 -0.3048)
							(mid -0.275042 -0.275042)
							(end -0.3048 -0.2032)
						)
						(arc
							(start -0.3048 0.2032)
							(mid -0.275042 0.275042)
							(end -0.2032 0.3048)
						)
						(arc
							(start 0.2032 0.3048)
							(mid 0.275042 0.275042)
							(end 0.3048 0.2032)
						)
					)
					(width 0)
					(fill yes)
				)
			)
		)
	)
	(footprint ""
		(layer "F.Cu")
		(at 14.378178 -43.193208 180)
		(property "Reference" "R519"
			(at 0 0 180)
			(layer "F.SilkS")
			(hide yes)
			(effects
				(font
					(size 1.27 1.27)
				)
			)
		)
		(property "Value" "10R2F-L-GP"
			(at 0.064008 -3.993896 180)
			(unlocked yes)
			(layer "F.Fab")
			(hide yes)
			(effects
				(font
					(size 1.016 1.016)
					(thickness 0.1524)
				)
			)
		)
		(property "Device Type" "R402H14"
			(at 0.064008 -5.517896 180)
			(unlocked yes)
			(layer "F.Fab")
			(hide yes)
			(effects
				(font
					(size 1.016 1.016)
					(thickness 0.1524)
				)
			)
		)
		(duplicate_pad_numbers_are_jumpers no)
		(fp_line
			(start 0.508 -0.9398)
			(end -0.508 -0.9398)
			(stroke
				(width 0.1524)
				(type default)
			)
			(layer "F.SilkS")
		)
		(fp_line
			(start -0.508 -0.9398)
			(end -0.508 0.9398)
			(stroke
				(width 0.1524)
				(type default)
			)
			(layer "F.SilkS")
		)
		(fp_rect
			(start -0.508 0.9398)
			(end 0.508 -0.9398)
			(stroke
				(width 0)
				(type default)
			)
			(fill no)
			(layer "F.CrtYd")
		)
		(fp_rect
			(start -0.508 0.9398)
			(end 0.508 -0.9398)
			(stroke
				(width 0)
				(type default)
			)
			(fill no)
			(layer "F.Fab")
		)
		(pad "1" smd custom
			(at 0 -0.4445 180)
			(size 0.1397 0.1397)
			(layers "F.Cu" "F.Mask" "F.Paste")
			(net "MB0_CM_SENSE_R1_P")
			(options
				(clearance outline)
				(anchor circle)
			)
			(primitives
				(gr_poly
					(pts
						(arc
							(start -0.1778 -0.2794)
							(mid -0.249642 -0.249642)
							(end -0.2794 -0.1778)
						)
						(arc
							(start -0.2794 0.1778)
							(mid -0.249642 0.249642)
							(end -0.1778 0.2794)
						)
						(arc
							(start 0.1778 0.2794)
							(mid 0.249642 0.249642)
							(end 0.2794 0.1778)
						)
						(arc
							(start 0.2794 -0.1778)
							(mid 0.249642 -0.249642)
							(end 0.1778 -0.2794)
						)
					)
					(width 0)
					(fill yes)
				)
			)
		)
		(pad "2" smd custom
			(at 0 0.4445 180)
			(size 0.1397 0.1397)
			(layers "F.Cu" "F.Mask" "F.Paste")
			(net "MB0_CM_SENSE_P")
			(options
				(clearance outline)
				(anchor circle)
			)
			(primitives
				(gr_poly
					(pts
						(arc
							(start -0.1778 -0.2794)
							(mid -0.249642 -0.249642)
							(end -0.2794 -0.1778)
						)
						(arc
							(start -0.2794 0.1778)
							(mid -0.249642 0.249642)
							(end -0.1778 0.2794)
						)
						(arc
							(start 0.1778 0.2794)
							(mid 0.249642 0.249642)
							(end 0.2794 0.1778)
						)
						(arc
							(start 0.2794 -0.1778)
							(mid 0.249642 -0.249642)
							(end 0.1778 -0.2794)
						)
					)
					(width 0)
					(fill yes)
				)
			)
		)
	)
	(footprint ""
		(layer "F.Cu")
		(at 109.7788 -86.741)
		(property "Reference" "TP52"
			(at 0 0 0)
			(layer "F.SilkS")
			(hide yes)
			(effects
				(font
					(size 1.27 1.27)
				)
			)
		)
		(property "Value" "TPAD28-2-GP"
			(at -0.0127 -1.6637 0)
			(unlocked yes)
			(layer "F.Fab")
			(hide yes)
			(effects
				(font
					(size 1.016 1.016)
					(thickness 0.1524)
				)
			)
		)
		(property "Device Type" "TPAD28"
			(at -0.0127 -3.1877 0)
			(unlocked yes)
			(layer "F.Fab")
			(hide yes)
			(effects
				(font
					(size 1.016 1.016)
					(thickness 0.1524)
				)
			)
		)
		(duplicate_pad_numbers_are_jumpers no)
		(fp_poly
			(pts
				(arc
					(start 0.3556 0)
					(mid -0.3556 0)
					(end 0.3556 0)
				)
			)
			(stroke
				(width 0)
				(type default)
			)
			(fill no)
			(layer "F.CrtYd")
		)
		(fp_poly
			(pts
				(arc
					(start 0.6096 0)
					(mid -0.6096 0)
					(end 0.6096 0)
				)
			)
			(stroke
				(width 0)
				(type default)
			)
			(fill no)
			(layer "F.Fab")
		)
		(pad "1" smd circle
			(at 0 0)
			(size 0.7112 0.7112)
			(layers "F.Cu" "F.Mask" "F.Paste")
			(net "XM_WBE_0#_TP")
		)
	)
	(footprint ""
		(layer "F.Cu")
		(at 65.278 -22.86 -90)
		(property "Reference" "R574"
			(at 0 0 270)
			(layer "F.SilkS")
			(hide yes)
			(effects
				(font
					(size 1.27 1.27)
				)
			)
		)
		(property "Value" "0R2J-2-GP"
			(at 0.064008 -3.993896 270)
			(unlocked yes)
			(layer "F.Fab")
			(hide yes)
			(effects
				(font
					(size 1.016 1.016)
					(thickness 0.1524)
				)
			)
		)
		(property "Device Type" "R402H16"
			(at 0.064008 -5.517896 270)
			(unlocked yes)
			(layer "F.Fab")
			(hide yes)
			(effects
				(font
					(size 1.016 1.016)
					(thickness 0.1524)
				)
			)
		)
		(duplicate_pad_numbers_are_jumpers no)
		(fp_line
			(start -0.508 -0.9398)
			(end -0.508 0.9398)
			(stroke
				(width 0.1524)
				(type default)
			)
			(layer "F.SilkS")
		)
		(fp_line
			(start 0.508 -0.9398)
			(end -0.508 -0.9398)
			(stroke
				(width 0.1524)
				(type default)
			)
			(layer "F.SilkS")
		)
		(fp_rect
			(start -0.508 0.9398)
			(end 0.508 -0.9398)
			(stroke
				(width 0)
				(type default)
			)
			(fill no)
			(layer "F.CrtYd")
		)
		(fp_rect
			(start -0.508 0.9398)
			(end 0.508 -0.9398)
			(stroke
				(width 0)
				(type default)
			)
			(fill no)
			(layer "F.Fab")
		)
		(pad "1" smd custom
			(at 0 -0.4445 270)
			(size 0.1397 0.1397)
			(layers "F.Cu" "F.Mask" "F.Paste")
			(net "SCC_STBY_PGOOD_U49")
			(options
				(clearance outline)
				(anchor circle)
			)
			(primitives
				(gr_poly
					(pts
						(arc
							(start -0.1778 -0.2794)
							(mid -0.249642 -0.249642)
							(end -0.2794 -0.1778)
						)
						(arc
							(start -0.2794 0.1778)
							(mid -0.249642 0.249642)
							(end -0.1778 0.2794)
						)
						(arc
							(start 0.1778 0.2794)
							(mid 0.249642 0.249642)
							(end 0.2794 0.1778)
						)
						(arc
							(start 0.2794 -0.1778)
							(mid 0.249642 -0.249642)
							(end 0.1778 -0.2794)
						)
					)
					(width 0)
					(fill yes)
				)
			)
		)
		(pad "2" smd custom
			(at 0 0.4445 270)
			(size 0.1397 0.1397)
			(layers "F.Cu" "F.Mask" "F.Paste")
			(net "SCC_FULL_PWR_EN_U49")
			(options
				(clearance outline)
				(anchor circle)
			)
			(primitives
				(gr_poly
					(pts
						(arc
							(start -0.1778 -0.2794)
							(mid -0.249642 -0.249642)
							(end -0.2794 -0.1778)
						)
						(arc
							(start -0.2794 0.1778)
							(mid -0.249642 0.249642)
							(end -0.1778 0.2794)
						)
						(arc
							(start 0.1778 0.2794)
							(mid 0.249642 0.249642)
							(end 0.2794 0.1778)
						)
						(arc
							(start 0.2794 -0.1778)
							(mid 0.249642 -0.249642)
							(end 0.1778 -0.2794)
						)
					)
					(width 0)
					(fill yes)
				)
			)
		)
	)
	(footprint ""
		(layer "F.Cu")
		(at 15.0114 -102.4001 -90)
		(property "Reference" "R528"
			(at 0 0 270)
			(layer "F.SilkS")
			(hide yes)
			(effects
				(font
					(size 1.27 1.27)
				)
			)
		)
		(property "Value" "10KR2F-2-GP"
			(at 0.064008 -3.993896 270)
			(unlocked yes)
			(layer "F.Fab")
			(hide yes)
			(effects
				(font
					(size 1.016 1.016)
					(thickness 0.1524)
				)
			)
		)
		(property "Device Type" "R402H16"
			(at 0.064008 -5.517896 270)
			(unlocked yes)
			(layer "F.Fab")
			(hide yes)
			(effects
				(font
					(size 1.016 1.016)
					(thickness 0.1524)
				)
			)
		)
		(duplicate_pad_numbers_are_jumpers no)
		(fp_line
			(start -0.508 -0.9398)
			(end -0.508 0.9398)
			(stroke
				(width 0.1524)
				(type default)
			)
			(layer "F.SilkS")
		)
		(fp_line
			(start 0.508 -0.9398)
			(end -0.508 -0.9398)
			(stroke
				(width 0.1524)
				(type default)
			)
			(layer "F.SilkS")
		)
		(fp_rect
			(start -0.508 0.9398)
			(end 0.508 -0.9398)
			(stroke
				(width 0)
				(type default)
			)
			(fill no)
			(layer "F.CrtYd")
		)
		(fp_rect
			(start -0.508 0.9398)
			(end 0.508 -0.9398)
			(stroke
				(width 0)
				(type default)
			)
			(fill no)
			(layer "F.Fab")
		)
		(pad "1" smd custom
			(at 0 -0.4445 270)
			(size 0.1397 0.1397)
			(layers "F.Cu" "F.Mask" "F.Paste")
			(net "U119_EN")
			(options
				(clearance outline)
				(anchor circle)
			)
			(primitives
				(gr_poly
					(pts
						(arc
							(start -0.1778 -0.2794)
							(mid -0.249642 -0.249642)
							(end -0.2794 -0.1778)
						)
						(arc
							(start -0.2794 0.1778)
							(mid -0.249642 0.249642)
							(end -0.1778 0.2794)
						)
						(arc
							(start 0.1778 0.2794)
							(mid 0.249642 0.249642)
							(end 0.2794 0.1778)
						)
						(arc
							(start 0.2794 -0.1778)
							(mid 0.249642 -0.249642)
							(end 0.1778 -0.2794)
						)
					)
					(width 0)
					(fill yes)
				)
			)
		)
		(pad "2" smd custom
			(at 0 0.4445 270)
			(size 0.1397 0.1397)
			(layers "F.Cu" "F.Mask" "F.Paste")
			(net "P3V3")
			(options
				(clearance outline)
				(anchor circle)
			)
			(primitives
				(gr_poly
					(pts
						(arc
							(start -0.1778 -0.2794)
							(mid -0.249642 -0.249642)
							(end -0.2794 -0.1778)
						)
						(arc
							(start -0.2794 0.1778)
							(mid -0.249642 0.249642)
							(end -0.1778 0.2794)
						)
						(arc
							(start 0.1778 0.2794)
							(mid 0.249642 0.249642)
							(end 0.2794 0.1778)
						)
						(arc
							(start 0.2794 -0.1778)
							(mid 0.249642 -0.249642)
							(end 0.1778 -0.2794)
						)
					)
					(width 0)
					(fill yes)
				)
			)
		)
	)
	(footprint ""
		(layer "F.Cu")
		(at 94.615 -75.9968 90)
		(property "Reference" "R124"
			(at 0 0 90)
			(layer "F.SilkS")
			(hide yes)
			(effects
				(font
					(size 1.27 1.27)
				)
			)
		)
		(property "Value" "4K75R2F-1-GP"
			(at 0.064008 -3.993896 90)
			(unlocked yes)
			(layer "F.Fab")
			(hide yes)
			(effects
				(font
					(size 1.016 1.016)
					(thickness 0.1524)
				)
			)
		)
		(property "Device Type" "R402H16"
			(at 0.064008 -5.517896 90)
			(unlocked yes)
			(layer "F.Fab")
			(hide yes)
			(effects
				(font
					(size 1.016 1.016)
					(thickness 0.1524)
				)
			)
		)
		(duplicate_pad_numbers_are_jumpers no)
		(fp_line
			(start 0.508 -0.9398)
			(end -0.508 -0.9398)
			(stroke
				(width 0.1524)
				(type default)
			)
			(layer "F.SilkS")
		)
		(fp_line
			(start -0.508 -0.9398)
			(end -0.508 0.9398)
			(stroke
				(width 0.1524)
				(type default)
			)
			(layer "F.SilkS")
		)
		(fp_rect
			(start -0.508 0.9398)
			(end 0.508 -0.9398)
			(stroke
				(width 0)
				(type default)
			)
			(fill no)
			(layer "F.CrtYd")
		)
		(fp_rect
			(start -0.508 0.9398)
			(end 0.508 -0.9398)
			(stroke
				(width 0)
				(type default)
			)
			(fill no)
			(layer "F.Fab")
		)
		(pad "1" smd custom
			(at 0 -0.4445 90)
			(size 0.1397 0.1397)
			(layers "F.Cu" "F.Mask" "F.Paste")
			(net "EXP_CLK_SEL0")
			(options
				(clearance outline)
				(anchor circle)
			)
			(primitives
				(gr_poly
					(pts
						(arc
							(start -0.1778 -0.2794)
							(mid -0.249642 -0.249642)
							(end -0.2794 -0.1778)
						)
						(arc
							(start -0.2794 0.1778)
							(mid -0.249642 0.249642)
							(end -0.1778 0.2794)
						)
						(arc
							(start 0.1778 0.2794)
							(mid 0.249642 0.249642)
							(end 0.2794 0.1778)
						)
						(arc
							(start 0.2794 -0.1778)
							(mid 0.249642 -0.249642)
							(end 0.1778 -0.2794)
						)
					)
					(width 0)
					(fill yes)
				)
			)
		)
		(pad "2" smd custom
			(at 0 0.4445 90)
			(size 0.1397 0.1397)
			(layers "F.Cu" "F.Mask" "F.Paste")
			(net "GND")
			(options
				(clearance outline)
				(anchor circle)
			)
			(primitives
				(gr_poly
					(pts
						(arc
							(start -0.1778 -0.2794)
							(mid -0.249642 -0.249642)
							(end -0.2794 -0.1778)
						)
						(arc
							(start -0.2794 0.1778)
							(mid -0.249642 0.249642)
							(end -0.1778 0.2794)
						)
						(arc
							(start 0.1778 0.2794)
							(mid 0.249642 0.249642)
							(end 0.2794 0.1778)
						)
						(arc
							(start 0.2794 -0.1778)
							(mid 0.249642 -0.249642)
							(end 0.1778 -0.2794)
						)
					)
					(width 0)
					(fill yes)
				)
			)
		)
	)
	(footprint ""
		(layer "F.Cu")
		(at 132.588 -89.7001 180)
		(property "Reference" "R39"
			(at 0 0 180)
			(layer "F.SilkS")
			(hide yes)
			(effects
				(font
					(size 1.27 1.27)
				)
			)
		)
		(property "Value" "4K7R2F-GP"
			(at 0.064008 -3.993896 180)
			(unlocked yes)
			(layer "F.Fab")
			(hide yes)
			(effects
				(font
					(size 1.016 1.016)
					(thickness 0.1524)
				)
			)
		)
		(property "Device Type" "R402H16"
			(at 0.064008 -5.517896 180)
			(unlocked yes)
			(layer "F.Fab")
			(hide yes)
			(effects
				(font
					(size 1.016 1.016)
					(thickness 0.1524)
				)
			)
		)
		(duplicate_pad_numbers_are_jumpers no)
		(fp_line
			(start 0.508 -0.9398)
			(end -0.508 -0.9398)
			(stroke
				(width 0.1524)
				(type default)
			)
			(layer "F.SilkS")
		)
		(fp_line
			(start -0.508 -0.9398)
			(end -0.508 0.9398)
			(stroke
				(width 0.1524)
				(type default)
			)
			(layer "F.SilkS")
		)
		(fp_rect
			(start -0.508 0.9398)
			(end 0.508 -0.9398)
			(stroke
				(width 0)
				(type default)
			)
			(fill no)
			(layer "F.CrtYd")
		)
		(fp_rect
			(start -0.508 0.9398)
			(end 0.508 -0.9398)
			(stroke
				(width 0)
				(type default)
			)
			(fill no)
			(layer "F.Fab")
		)
		(pad "1" smd custom
			(at 0 -0.4445 180)
			(size 0.1397 0.1397)
			(layers "F.Cu" "F.Mask" "F.Paste")
			(net "EXP_SIO_D_IN")
			(options
				(clearance outline)
				(anchor circle)
			)
			(primitives
				(gr_poly
					(pts
						(arc
							(start -0.1778 -0.2794)
							(mid -0.249642 -0.249642)
							(end -0.2794 -0.1778)
						)
						(arc
							(start -0.2794 0.1778)
							(mid -0.249642 0.249642)
							(end -0.1778 0.2794)
						)
						(arc
							(start 0.1778 0.2794)
							(mid 0.249642 0.249642)
							(end 0.2794 0.1778)
						)
						(arc
							(start 0.2794 -0.1778)
							(mid 0.249642 -0.249642)
							(end 0.1778 -0.2794)
						)
					)
					(width 0)
					(fill yes)
				)
			)
		)
		(pad "2" smd custom
			(at 0 0.4445 180)
			(size 0.1397 0.1397)
			(layers "F.Cu" "F.Mask" "F.Paste")
			(net "P1V8_E")
			(options
				(clearance outline)
				(anchor circle)
			)
			(primitives
				(gr_poly
					(pts
						(arc
							(start -0.1778 -0.2794)
							(mid -0.249642 -0.249642)
							(end -0.2794 -0.1778)
						)
						(arc
							(start -0.2794 0.1778)
							(mid -0.249642 0.249642)
							(end -0.1778 0.2794)
						)
						(arc
							(start 0.1778 0.2794)
							(mid 0.249642 0.249642)
							(end 0.2794 0.1778)
						)
						(arc
							(start 0.2794 -0.1778)
							(mid 0.249642 -0.249642)
							(end 0.1778 -0.2794)
						)
					)
					(width 0)
					(fill yes)
				)
			)
		)
	)
)
